# T6G (Grand Teton) — schematic netlist excerpt (pin names and nets, part order shuffled) for the footprints in the layout excerpt that follows; sources: Cadence DE-HDL packaged netlist, KiCad conversion of 04192023_DAF0TMB3IC0_F0TG_MB_C_brd_V02_OCP.brd

PU10  ISL99390FRZTR5935  ISL99390FRZ-TR5935 IC  pkg QFN21_6X5XB  page 196
  VOS  = PVDDCR_CPU0_P0_VOS6
  AGND  = GND
  VCC  = PVDDCR_CPU0_P0_VCC6
  PVCC  = PVDDCR_CPU0_P0_PVCC
  PGND1  = GND
  GL1  = NC_PVDDCR_CPU0_P0_GL1_6
  PGND2  = GND
  SW  = SW_PVDDCR_CPU0_P0_SW6
  VIN1  = SW_P12V_AUX_PVDDCR_CPU0_P0_FLT
  VIN2  = SW_P12V_AUX_PVDDCR_CPU0_P0_FLT
  DNC  = NC_PVDDCR_CPU0_P0_DNC6
  PHASE  = SW_PVDDCR_CPU0_P0_PH6
  BOOT  = SW_PVDDCR_CPU0_P0_BOOT6
  PWM  = PVDDCR_CPU0_P0_PWM6
  EN  = PVDDCR_CPU0_P0_VCC6
  TOUT_FLT  = PVDDCR_CPU0_P0_TEMP0
  LSET  = PVDDCR_CPU0_P0_LSET6
  IOUT  = PVDDCR_CPU0_P0_IMON6
  REFIN  = PVDDCR_CPU0_P0_VCCS
  PGND3  = GND
  GL2  = NC_PVDDCR_CPU0_P0_GL2_6

(kicad_pcb
	(version 20260206)
	(generator "pcbnew")
	(generator_version "10.0")
	(general
		(thickness 1.6)
		(legacy_teardrops no)
	)
	(paper "A4")
	(title_block
		(title "04192023_DAF0TMB3IC0_F0TG_MB_C_brd_V02_OCP.brd")
		(comment 1 "Grand Teton / footprints 4690-4690 of 8354")
	)
	(layers
		(0 "F.Cu" signal "TOP")
		(4 "In1.Cu" signal "GND")
		(6 "In2.Cu" signal "IN1")
		(8 "In3.Cu" signal "GND1")
		(10 "In4.Cu" signal "IN2")
		(12 "In5.Cu" signal "GND2")
		(14 "In6.Cu" signal "IN3")
		(16 "In7.Cu" signal "GND3")
		(18 "In8.Cu" signal "VCC")
		(20 "In9.Cu" signal "VCC1")
		(22 "In10.Cu" signal "GND4")
		(24 "In11.Cu" signal "IN4")
		(26 "In12.Cu" signal "GND5")
		(28 "In13.Cu" signal "IN5")
		(30 "In14.Cu" signal "GND6")
		(32 "In15.Cu" signal "IN6")
		(34 "In16.Cu" signal "GND7")
		(2 "B.Cu" signal "BOTTOM")
		(9 "F.Adhes" user "F.Adhesive")
		(11 "B.Adhes" user "B.Adhesive")
		(13 "F.Paste" user "Package Geometry/Pastemask Top")
		(15 "B.Paste" user "Package Geometry/Pastemask Bottom")
		(5 "F.SilkS" user "Ref Des/Silkscreen Top")
		(7 "B.SilkS" user "Ref Des/Silkscreen Bottom")
		(1 "F.Mask" user "Board Geometry/Soldermask Top")
		(3 "B.Mask" user "Board Geometry/Soldermask Bottom")
		(17 "Dwgs.User" user "User.Drawings")
		(19 "Cmts.User" user "User.Comments")
		(21 "Eco1.User" user "User.Eco1")
		(23 "Eco2.User" user "User.Eco2")
		(25 "Edge.Cuts" user "Board Geometry/Outline")
		(27 "Margin" user)
		(31 "F.CrtYd" user "Package Geometry/Place Bound Top")
		(29 "B.CrtYd" user "Package Geometry/Place Bound Bottom")
		(35 "F.Fab" user "Ref Des/Assembly Top")
		(33 "B.Fab" user "Ref Des/Assembly Bottom")
	)
	(footprint ""
		(layer "F.Cu")
		(at 347.727778 -161.139378 180)
		(property "Reference" "PU10"
			(at 6.094476 -1.518666 0)
			(unlocked yes)
			(layer "F.SilkS")
			(effects
				(font
					(size 0.7874 0.5842)
					(thickness 0.1524)
				)
				(justify left)
			)
		)
		(property "Value" ""
			(at 0 0 180)
			(layer "F.Fab")
			(effects
				(font
					(size 1.27 1.27)
				)
			)
		)
		(duplicate_pad_numbers_are_jumpers no)
		(fp_line
			(start 2.500122 2.999994)
			(end 2.2987 2.999994)
			(stroke
				(width 0.1524)
				(type default)
			)
			(layer "F.SilkS")
		)
		(fp_line
			(start 2.500122 2.339594)
			(end 2.500122 2.999994)
			(stroke
				(width 0.1524)
				(type default)
			)
			(layer "F.SilkS")
		)
		(fp_line
			(start 2.500122 -2.999994)
			(end 2.500122 -2.44348)
			(stroke
				(width 0.1524)
				(type default)
			)
			(layer "F.SilkS")
		)
		(fp_line
			(start 2.31394 -2.999994)
			(end 2.500122 -2.999994)
			(stroke
				(width 0.1524)
				(type default)
			)
			(layer "F.SilkS")
		)
		(fp_line
			(start -2.2987 2.999994)
			(end -2.500122 2.999994)
			(stroke
				(width 0.1524)
				(type default)
			)
			(layer "F.SilkS")
		)
		(fp_line
			(start -2.500122 2.999994)
			(end -2.500122 2.339594)
			(stroke
				(width 0.1524)
				(type default)
			)
			(layer "F.SilkS")
		)
		(fp_line
			(start -2.500122 0.6604)
			(end -2.500122 0.229108)
			(stroke
				(width 0.1524)
				(type default)
			)
			(layer "F.SilkS")
		)
		(fp_line
			(start -2.500122 -2.529078)
			(end -2.500122 -2.999994)
			(stroke
				(width 0.1524)
				(type default)
			)
			(layer "F.SilkS")
		)
		(fp_line
			(start -2.500122 -2.999994)
			(end -2.24409 -2.999994)
			(stroke
				(width 0.1524)
				(type default)
			)
			(layer "F.SilkS")
		)
		(fp_poly
			(pts
				(xy -2.644902 -2.457196) (xy -3.412236 -2.712974) (xy -2.90068 -3.22453)
			)
			(stroke
				(width 0)
				(type default)
			)
			(fill yes)
			(layer "F.SilkS")
		)
		(fp_line
			(start 2.500122 2.999994)
			(end -2.500122 2.999994)
			(stroke
				(width 0.1)
				(type default)
			)
			(layer "F.Fab")
		)
		(fp_line
			(start 2.500122 -2.999994)
			(end 2.500122 2.999994)
			(stroke
				(width 0.1)
				(type default)
			)
			(layer "F.Fab")
		)
		(fp_line
			(start -2.500122 2.999994)
			(end -2.500122 -2.999994)
			(stroke
				(width 0.1)
				(type default)
			)
			(layer "F.Fab")
		)
		(fp_line
			(start -2.500122 -2.999994)
			(end 2.500122 -2.999994)
			(stroke
				(width 0.1)
				(type default)
			)
			(layer "F.Fab")
		)
		(fp_poly
			(pts
				(xy -4.218432 -2.783078) (xy -4.218432 -1.767078) (xy -3.202432 -2.275078)
			)
			(stroke
				(width 0)
				(type default)
			)
			(fill yes)
			(layer "F.Fab")
		)
		(pad "1" smd rect
			(at -2.400046 -2.275078 270)
			(size 0.2286 0.6096)
			(layers "F.Cu" "F.Mask" "F.Paste")
			(net "PVDDCR_CPU0_P0_VOS6")
		)
		(pad "2" smd rect
			(at -2.400046 -1.82499 270)
			(size 0.2286 0.6096)
			(layers "F.Cu" "F.Mask" "F.Paste")
			(net "GND")
		)
		(pad "3" smd rect
			(at -2.400046 -1.374902 270)
			(size 0.2286 0.6096)
			(layers "F.Cu" "F.Mask" "F.Paste")
			(net "PVDDCR_CPU0_P0_VCC6")
		)
		(pad "4" smd rect
			(at -2.400046 -0.925068 270)
			(size 0.2286 0.6096)
			(layers "F.Cu" "F.Mask" "F.Paste")
			(net "PVDDCR_CPU0_P0_PVCC")
		)
		(pad "5" smd rect
			(at -2.400046 -0.47498 270)
			(size 0.2286 0.6096)
			(layers "F.Cu" "F.Mask" "F.Paste")
			(net "GND")
		)
		(pad "6" smd rect
			(at -2.400046 -0.024892 270)
			(size 0.2286 0.6096)
			(layers "F.Cu" "F.Mask" "F.Paste")
			(net "NC_PVDDCR_CPU0_P0_GL1_6")
		)
		(pad "7_9-20_24" smd circle
			(at 0 1.150112 270)
			(size 0 0)
			(layers "F.Cu" "F.Mask" "F.Paste")
			(net "GND")
		)
		(pad "10_19" smd rect
			(at 0 2.899918 270)
			(size 0.6096 4.318)
			(layers "F.Cu" "F.Mask" "F.Paste")
			(net "SW_PVDDCR_CPU0_P0_SW6")
		)
		(pad "25_29" smd rect
			(at 1.549908 -1.279906 90)
			(size 2.0574 2.3114)
			(layers "F.Cu" "F.Mask" "F.Paste")
			(net "SW_P12V_AUX_PVDDCR_CPU0_P0_FLT")
		)
		(pad "30" smd rect
			(at 2.05994 -2.899918 180)
			(size 0.2286 0.6096)
			(layers "F.Cu" "F.Mask" "F.Paste")
			(net "SW_P12V_AUX_PVDDCR_CPU0_P0_FLT")
		)
		(pad "31" smd rect
			(at 1.610106 -2.899918 180)
			(size 0.2286 0.6096)
			(layers "F.Cu" "F.Mask" "F.Paste")
			(net "NC_PVDDCR_CPU0_P0_DNC6")
		)
		(pad "32" smd rect
			(at 1.160018 -2.899918 180)
			(size 0.2286 0.6096)
			(layers "F.Cu" "F.Mask" "F.Paste")
			(net "SW_PVDDCR_CPU0_P0_PH6")
		)
		(pad "33" smd rect
			(at 0.70993 -2.899918 180)
			(size 0.2286 0.6096)
			(layers "F.Cu" "F.Mask" "F.Paste")
			(net "SW_PVDDCR_CPU0_P0_BOOT6")
		)
		(pad "34" smd rect
			(at 0.260096 -2.899918 180)
			(size 0.2286 0.6096)
			(layers "F.Cu" "F.Mask" "F.Paste")
			(net "PVDDCR_CPU0_P0_PWM6")
		)
		(pad "35" smd rect
			(at -0.189992 -2.899918 180)
			(size 0.2286 0.6096)
			(layers "F.Cu" "F.Mask" "F.Paste")
			(net "PVDDCR_CPU0_P0_VCC6")
		)
		(pad "36" smd rect
			(at -0.64008 -2.899918 180)
			(size 0.2286 0.6096)
			(layers "F.Cu" "F.Mask" "F.Paste")
			(net "PVDDCR_CPU0_P0_TEMP0")
		)
		(pad "37" smd rect
			(at -1.089914 -2.899918 180)
			(size 0.2286 0.6096)
			(layers "F.Cu" "F.Mask" "F.Paste")
			(net "PVDDCR_CPU0_P0_LSET6")
		)
		(pad "38" smd rect
			(at -1.540002 -2.899918 180)
			(size 0.2286 0.6096)
			(layers "F.Cu" "F.Mask" "F.Paste")
			(net "PVDDCR_CPU0_P0_IMON6")
		)
		(pad "39" smd rect
			(at -1.99009 -2.899918 180)
			(size 0.2286 0.6096)
			(layers "F.Cu" "F.Mask" "F.Paste")
			(net "PVDDCR_CPU0_P0_VCCS")
		)
		(pad "40" smd rect
			(at -0.87503 -1.27508 180)
			(size 1.7526 1.9558)
			(layers "F.Cu" "F.Mask" "F.Paste")
			(net "GND")
		)
		(pad "41" smd rect
			(at -1.525016 0.249936 90)
			(size 0.3048 0.4572)
			(layers "F.Cu" "F.Mask" "F.Paste")
			(net "NC_PVDDCR_CPU0_P0_GL2_6")
		)
		(zone
			(layer "F.Cu")
			(hatch none 0.5)
			(connect_pads
				(clearance 0)
			)
			(min_thickness 0.25)
			(keepout
				(tracks not_allowed)
				(vias allowed)
				(pads allowed)
				(copperpour not_allowed)
				(footprints allowed)
			)
			(placement
				(enabled no)
				(sheetname "")
			)
			(fill
				(thermal_gap 0.5)
				(thermal_bridge_width 0.5)
				(island_removal_mode 0)
			)
			(polygon
				(pts
					(xy 350.2279 -163.726114) (xy 350.2279 -163.390072) (xy 345.227656 -163.390072) (xy 345.227656 -163.711128)
					(xy 345.517978 -163.711128) (xy 345.517978 -163.683696) (xy 349.937578 -163.683696) (xy 349.937578 -163.726114)
				)
			)
		)
		(zone
			(layer "F.Cu")
			(hatch none 0.5)
			(connect_pads
				(clearance 0)
			)
			(min_thickness 0.25)
			(keepout
				(tracks not_allowed)
				(vias allowed)
				(pads allowed)
				(copperpour not_allowed)
				(footprints allowed)
			)
			(placement
				(enabled no)
				(sheetname "")
			)
			(fill
				(thermal_gap 0.5)
				(thermal_bridge_width 0.5)
				(island_removal_mode 0)
			)
			(polygon
				(pts
					(xy 347.675708 -160.892998) (xy 347.675708 -158.835598) (xy 349.529908 -158.835598) (xy 349.529908 -159.076644)
					(xy 349.772224 -159.076644) (xy 349.772224 -158.59506) (xy 345.886024 -158.59506) (xy 345.886024 -158.779972)
					(xy 347.38437 -158.779972) (xy 347.38437 -160.938972) (xy 345.227656 -160.938972) (xy 345.227656 -161.188654)
					(xy 347.380052 -161.188654)
				)
			)
		)
	)
)
